(kicad_pcb
	(version 20260206)
	(generator "pcbnew")
	(generator_version "10.0")
	(general
		(thickness 1.6)
		(legacy_teardrops no)
	)
	(paper "A4")
	(title_block
		(title "Wiwynn_Tioga_Pass_MB.brd")
		(comment 1 "Tioga Pass / footprints 484-491 of 4770")
	)
	(layers
		(0 "F.Cu" signal "TOP")
		(4 "In1.Cu" signal "L2GND")
		(6 "In2.Cu" signal "L3")
		(8 "In3.Cu" signal "L4GND")
		(10 "In4.Cu" signal "L5")
		(12 "In5.Cu" signal "L6GND")
		(14 "In6.Cu" signal "L7VCC")
		(16 "In7.Cu" signal "L8VCC")
		(18 "In8.Cu" signal "L9GND")
		(20 "In9.Cu" signal "L10")
		(22 "In10.Cu" signal "L11GND")
		(24 "In11.Cu" signal "L12")
		(26 "In12.Cu" signal "L13GND")
		(2 "B.Cu" signal "BOTTOM")
		(9 "F.Adhes" user "F.Adhesive")
		(11 "B.Adhes" user "B.Adhesive")
		(13 "F.Paste" user "Package Geometry/Pastemask Top")
		(15 "B.Paste" user "Package Geometry/Pastemask Bottom")
		(5 "F.SilkS" user "Ref Des/Silkscreen Top")
		(7 "B.SilkS" user "Ref Des/Silkscreen Bottom")
		(1 "F.Mask" user "Board Geometry/Soldermask Top")
		(3 "B.Mask" user "Board Geometry/Soldermask Bottom")
		(17 "Dwgs.User" user "User.Drawings")
		(19 "Cmts.User" user "User.Comments")
		(21 "Eco1.User" user "User.Eco1")
		(23 "Eco2.User" user "User.Eco2")
		(25 "Edge.Cuts" user "Board Geometry/Outline")
		(27 "Margin" user)
		(31 "F.CrtYd" user "Package Geometry/Place Bound Top")
		(29 "B.CrtYd" user "Package Geometry/Place Bound Bottom")
		(35 "F.Fab" user "Ref Des/Assembly Top")
		(33 "B.Fab" user "Ref Des/Assembly Bottom")
	)
	(footprint ""
		(layer "F.Cu")
		(at 340.233 -23.749)
		(property "Reference" "R7F14"
			(at 0 0 0)
			(layer "F.SilkS")
			(hide yes)
			(effects
				(font
					(size 1.27 1.27)
				)
			)
		)
		(property "Value" ""
			(at 0 0 0)
			(layer "F.Fab")
			(effects
				(font
					(size 1.27 1.27)
				)
			)
		)
		(duplicate_pad_numbers_are_jumpers no)
		(fp_rect
			(start -0.2794 0.9906)
			(end 0.2794 -0.1016)
			(stroke
				(width 0)
				(type default)
			)
			(fill no)
			(layer "F.CrtYd")
		)
		(fp_line
			(start -0.2794 -0.1016)
			(end -0.2794 0.9906)
			(stroke
				(width 0.1)
				(type default)
			)
			(layer "F.Fab")
		)
		(fp_line
			(start -0.2794 0.9906)
			(end 0.2794 0.9906)
			(stroke
				(width 0.1)
				(type default)
			)
			(layer "F.Fab")
		)
		(fp_line
			(start 0.2794 -0.1016)
			(end -0.2794 -0.1016)
			(stroke
				(width 0.1)
				(type default)
			)
			(layer "F.Fab")
		)
		(fp_line
			(start 0.2794 0.9906)
			(end 0.2794 -0.1016)
			(stroke
				(width 0.1)
				(type default)
			)
			(layer "F.Fab")
		)
		(pad "1" smd rect
			(at 0 0)
			(size 0.508 0.508)
			(layers "F.Cu" "F.Mask" "F.Paste")
			(net "FM_PVPP_CPU0_EN")
		)
		(pad "2" smd rect
			(at 0 0.889)
			(size 0.508 0.508)
			(layers "F.Cu" "F.Mask" "F.Paste")
			(net "GND")
		)
		(zone
			(layer "F.Cu")
			(hatch none 0.5)
			(connect_pads
				(clearance 0)
			)
			(min_thickness 0.25)
			(keepout
				(tracks allowed)
				(vias not_allowed)
				(pads allowed)
				(copperpour not_allowed)
				(footprints allowed)
			)
			(placement
				(enabled no)
				(sheetname "")
			)
			(fill
				(thermal_gap 0.5)
				(thermal_bridge_width 0.5)
				(island_removal_mode 0)
			)
			(polygon
				(pts
					(xy 339.979 -23.114) (xy 340.487 -23.114) (xy 340.487 -23.495) (xy 339.979 -23.495)
				)
			)
		)
		(zone
			(layer "F.Cu")
			(hatch none 0.5)
			(connect_pads
				(clearance 0)
			)
			(min_thickness 0.25)
			(keepout
				(tracks not_allowed)
				(vias allowed)
				(pads allowed)
				(copperpour not_allowed)
				(footprints allowed)
			)
			(placement
				(enabled no)
				(sheetname "")
			)
			(fill
				(thermal_gap 0.5)
				(thermal_bridge_width 0.5)
				(island_removal_mode 0)
			)
			(polygon
				(pts
					(xy 339.979 -23.114) (xy 340.487 -23.114) (xy 340.487 -23.495) (xy 339.979 -23.495)
				)
			)
		)
	)
	(footprint ""
		(layer "F.Cu")
		(at 204.4192 -77.47 -90)
		(property "Reference" "CT41"
			(at -0.8382 -0.67818 270)
			(unlocked yes)
			(layer "F.SilkS")
			(effects
				(font
					(size 0.4064 0.254)
					(thickness 0.1524)
				)
				(justify left)
			)
		)
		(property "Value" ""
			(at 0 0 270)
			(layer "F.Fab")
			(effects
				(font
					(size 1.27 1.27)
				)
			)
		)
		(duplicate_pad_numbers_are_jumpers no)
		(fp_poly
			(pts
				(xy 0.3048 -0.1016) (xy 0.3048 0.9906) (xy -0.3048 0.9906) (xy -0.3048 -0.1016)
			)
			(stroke
				(width 0)
				(type default)
			)
			(fill no)
			(layer "F.CrtYd")
		)
		(fp_line
			(start -0.3048 0.9906)
			(end 0.3048 0.9906)
			(stroke
				(width 0.1)
				(type default)
			)
			(layer "F.Fab")
		)
		(fp_line
			(start 0.3048 0.9906)
			(end 0.3048 -0.1016)
			(stroke
				(width 0.1)
				(type default)
			)
			(layer "F.Fab")
		)
		(fp_line
			(start -0.3048 -0.1016)
			(end -0.3048 0.9906)
			(stroke
				(width 0.1)
				(type default)
			)
			(layer "F.Fab")
		)
		(fp_line
			(start 0.3048 -0.1016)
			(end -0.3048 -0.1016)
			(stroke
				(width 0.1)
				(type default)
			)
			(layer "F.Fab")
		)
		(pad "1" smd rect
			(at 0 0 270)
			(size 0.508 0.508)
			(layers "F.Cu" "F.Mask" "F.Paste")
			(net "VR_PVCCIN_CPU0_PHASE4")
		)
		(pad "2" smd rect
			(at 0 0.889 270)
			(size 0.508 0.508)
			(layers "F.Cu" "F.Mask" "F.Paste")
			(net "VR_PVCCIN_CPU0_PHASE4_RC")
		)
		(zone
			(layer "F.Cu")
			(hatch none 0.5)
			(connect_pads
				(clearance 0)
			)
			(min_thickness 0.25)
			(keepout
				(tracks not_allowed)
				(vias allowed)
				(pads allowed)
				(copperpour not_allowed)
				(footprints allowed)
			)
			(placement
				(enabled no)
				(sheetname "")
			)
			(fill
				(thermal_gap 0.5)
				(thermal_bridge_width 0.5)
				(island_removal_mode 0)
			)
			(polygon
				(pts
					(xy 203.7842 -77.724) (xy 203.7842 -77.216) (xy 204.1652 -77.216) (xy 204.1652 -77.724)
				)
			)
		)
		(zone
			(layer "F.Cu")
			(hatch none 0.5)
			(connect_pads
				(clearance 0)
			)
			(min_thickness 0.25)
			(keepout
				(tracks allowed)
				(vias not_allowed)
				(pads allowed)
				(copperpour not_allowed)
				(footprints allowed)
			)
			(placement
				(enabled no)
				(sheetname "")
			)
			(fill
				(thermal_gap 0.5)
				(thermal_bridge_width 0.5)
				(island_removal_mode 0)
			)
			(polygon
				(pts
					(xy 204.1652 -77.724) (xy 204.1652 -77.216) (xy 203.7842 -77.216) (xy 203.7842 -77.724)
				)
			)
		)
	)
	(footprint ""
		(layer "F.Cu")
		(at 342.4428 -127.5588 90)
		(property "Reference" "C7B10"
			(at 0 0 90)
			(layer "F.SilkS")
			(hide yes)
			(effects
				(font
					(size 1.27 1.27)
				)
			)
		)
		(property "Value" ""
			(at 0 0 90)
			(layer "F.Fab")
			(effects
				(font
					(size 1.27 1.27)
				)
			)
		)
		(duplicate_pad_numbers_are_jumpers no)
		(fp_poly
			(pts
				(xy 0.3048 -0.1016) (xy 0.3048 0.9906) (xy -0.3048 0.9906) (xy -0.3048 -0.1016)
			)
			(stroke
				(width 0)
				(type default)
			)
			(fill no)
			(layer "F.CrtYd")
		)
		(fp_line
			(start 0.3048 -0.1016)
			(end -0.3048 -0.1016)
			(stroke
				(width 0.1)
				(type default)
			)
			(layer "F.Fab")
		)
		(fp_line
			(start -0.3048 -0.1016)
			(end -0.3048 0.9906)
			(stroke
				(width 0.1)
				(type default)
			)
			(layer "F.Fab")
		)
		(fp_line
			(start 0.3048 0.9906)
			(end 0.3048 -0.1016)
			(stroke
				(width 0.1)
				(type default)
			)
			(layer "F.Fab")
		)
		(fp_line
			(start -0.3048 0.9906)
			(end 0.3048 0.9906)
			(stroke
				(width 0.1)
				(type default)
			)
			(layer "F.Fab")
		)
		(pad "1" smd rect
			(at 0 0 90)
			(size 0.508 0.508)
			(layers "F.Cu" "F.Mask" "F.Paste")
			(net "VR_FB_PVPP_DEF")
		)
		(pad "2" smd rect
			(at 0 0.889 90)
			(size 0.508 0.508)
			(layers "F.Cu" "F.Mask" "F.Paste")
			(net "VR_COMP_PVPP_DEF_3")
		)
		(zone
			(layer "F.Cu")
			(hatch none 0.5)
			(connect_pads
				(clearance 0)
			)
			(min_thickness 0.25)
			(keepout
				(tracks allowed)
				(vias not_allowed)
				(pads allowed)
				(copperpour not_allowed)
				(footprints allowed)
			)
			(placement
				(enabled no)
				(sheetname "")
			)
			(fill
				(thermal_gap 0.5)
				(thermal_bridge_width 0.5)
				(island_removal_mode 0)
			)
			(polygon
				(pts
					(xy 342.6968 -127.3048) (xy 342.6968 -127.8128) (xy 343.0778 -127.8128) (xy 343.0778 -127.3048)
				)
			)
		)
		(zone
			(layer "F.Cu")
			(hatch none 0.5)
			(connect_pads
				(clearance 0)
			)
			(min_thickness 0.25)
			(keepout
				(tracks not_allowed)
				(vias allowed)
				(pads allowed)
				(copperpour not_allowed)
				(footprints allowed)
			)
			(placement
				(enabled no)
				(sheetname "")
			)
			(fill
				(thermal_gap 0.5)
				(thermal_bridge_width 0.5)
				(island_removal_mode 0)
			)
			(polygon
				(pts
					(xy 343.0778 -127.3048) (xy 343.0778 -127.8128) (xy 342.6968 -127.8128) (xy 342.6968 -127.3048)
				)
			)
		)
	)
	(footprint ""
		(layer "F.Cu")
		(at 462.114392 -37.956998)
		(property "Reference" "R9F11"
			(at 0 0 0)
			(layer "F.SilkS")
			(hide yes)
			(effects
				(font
					(size 1.27 1.27)
				)
			)
		)
		(property "Value" ""
			(at 0 0 0)
			(layer "F.Fab")
			(effects
				(font
					(size 1.27 1.27)
				)
			)
		)
		(duplicate_pad_numbers_are_jumpers no)
		(fp_poly
			(pts
				(xy -0.2794 -0.1016) (xy 0.2794 -0.1016) (xy 0.2794 0.9906) (xy -0.2794 0.9906)
			)
			(stroke
				(width 0)
				(type default)
			)
			(fill no)
			(layer "F.CrtYd")
		)
		(fp_line
			(start -0.2794 -0.1016)
			(end -0.2794 0.9906)
			(stroke
				(width 0.1)
				(type default)
			)
			(layer "F.Fab")
		)
		(fp_line
			(start -0.2794 0.9906)
			(end 0.2794 0.9906)
			(stroke
				(width 0.1)
				(type default)
			)
			(layer "F.Fab")
		)
		(fp_line
			(start 0.2794 -0.1016)
			(end -0.2794 -0.1016)
			(stroke
				(width 0.1)
				(type default)
			)
			(layer "F.Fab")
		)
		(fp_line
			(start 0.2794 0.9906)
			(end 0.2794 -0.1016)
			(stroke
				(width 0.1)
				(type default)
			)
			(layer "F.Fab")
		)
		(pad "1" smd rect
			(at 0 0)
			(size 0.508 0.508)
			(layers "F.Cu" "F.Mask" "F.Paste")
			(net "PWRGD_P1V15_BMC_STBY_R")
		)
		(pad "2" smd rect
			(at 0 0.889)
			(size 0.508 0.508)
			(layers "F.Cu" "F.Mask" "F.Paste")
			(net "PWRGD_P1V15_BMC_STBY")
		)
		(zone
			(layer "F.Cu")
			(hatch none 0.5)
			(connect_pads
				(clearance 0)
			)
			(min_thickness 0.25)
			(keepout
				(tracks allowed)
				(vias not_allowed)
				(pads allowed)
				(copperpour not_allowed)
				(footprints allowed)
			)
			(placement
				(enabled no)
				(sheetname "")
			)
			(fill
				(thermal_gap 0.5)
				(thermal_bridge_width 0.5)
				(island_removal_mode 0)
			)
			(polygon
				(pts
					(xy 461.860392 -37.702998) (xy 462.368392 -37.702998) (xy 462.368392 -37.321998) (xy 461.860392 -37.321998)
				)
			)
		)
		(zone
			(layer "F.Cu")
			(hatch none 0.5)
			(connect_pads
				(clearance 0)
			)
			(min_thickness 0.25)
			(keepout
				(tracks not_allowed)
				(vias allowed)
				(pads allowed)
				(copperpour not_allowed)
				(footprints allowed)
			)
			(placement
				(enabled no)
				(sheetname "")
			)
			(fill
				(thermal_gap 0.5)
				(thermal_bridge_width 0.5)
				(island_removal_mode 0)
			)
			(polygon
				(pts
					(xy 461.860392 -37.321998) (xy 462.368392 -37.321998) (xy 462.368392 -37.702998) (xy 461.860392 -37.702998)
				)
			)
		)
	)
	(footprint ""
		(layer "F.Cu")
		(at 454.025 -37.846 180)
		(property "Reference" "R9E24"
			(at 0 0 180)
			(layer "F.SilkS")
			(hide yes)
			(effects
				(font
					(size 1.27 1.27)
				)
			)
		)
		(property "Value" ""
			(at 0 0 180)
			(layer "F.Fab")
			(effects
				(font
					(size 1.27 1.27)
				)
			)
		)
		(duplicate_pad_numbers_are_jumpers no)
		(fp_poly
			(pts
				(xy -0.2794 -0.1016) (xy 0.2794 -0.1016) (xy 0.2794 0.9906) (xy -0.2794 0.9906)
			)
			(stroke
				(width 0)
				(type default)
			)
			(fill no)
			(layer "F.CrtYd")
		)
		(fp_line
			(start 0.2794 0.9906)
			(end 0.2794 -0.1016)
			(stroke
				(width 0.1)
				(type default)
			)
			(layer "F.Fab")
		)
		(fp_line
			(start 0.2794 -0.1016)
			(end -0.2794 -0.1016)
			(stroke
				(width 0.1)
				(type default)
			)
			(layer "F.Fab")
		)
		(fp_line
			(start -0.2794 0.9906)
			(end 0.2794 0.9906)
			(stroke
				(width 0.1)
				(type default)
			)
			(layer "F.Fab")
		)
		(fp_line
			(start -0.2794 -0.1016)
			(end -0.2794 0.9906)
			(stroke
				(width 0.1)
				(type default)
			)
			(layer "F.Fab")
		)
		(pad "1" smd rect
			(at 0 0 180)
			(size 0.508 0.508)
			(layers "F.Cu" "F.Mask" "F.Paste")
			(net "FM_HEARTBEAT_LED_A")
		)
		(pad "2" smd rect
			(at 0 0.889 180)
			(size 0.508 0.508)
			(layers "F.Cu" "F.Mask" "F.Paste")
			(net "P3V3_STBY")
		)
		(zone
			(layer "F.Cu")
			(hatch none 0.5)
			(connect_pads
				(clearance 0)
			)
			(min_thickness 0.25)
			(keepout
				(tracks not_allowed)
				(vias allowed)
				(pads allowed)
				(copperpour not_allowed)
				(footprints allowed)
			)
			(placement
				(enabled no)
				(sheetname "")
			)
			(fill
				(thermal_gap 0.5)
				(thermal_bridge_width 0.5)
				(island_removal_mode 0)
			)
			(polygon
				(pts
					(xy 454.279 -38.481) (xy 453.771 -38.481) (xy 453.771 -38.1) (xy 454.279 -38.1)
				)
			)
		)
		(zone
			(layer "F.Cu")
			(hatch none 0.5)
			(connect_pads
				(clearance 0)
			)
			(min_thickness 0.25)
			(keepout
				(tracks allowed)
				(vias not_allowed)
				(pads allowed)
				(copperpour not_allowed)
				(footprints allowed)
			)
			(placement
				(enabled no)
				(sheetname "")
			)
			(fill
				(thermal_gap 0.5)
				(thermal_bridge_width 0.5)
				(island_removal_mode 0)
			)
			(polygon
				(pts
					(xy 454.279 -38.1) (xy 453.771 -38.1) (xy 453.771 -38.481) (xy 454.279 -38.481)
				)
			)
		)
	)
	(footprint ""
		(layer "F.Cu")
		(at 463.3849 -23.9903 180)
		(property "Reference" "C8E17"
			(at 0 0 180)
			(layer "F.SilkS")
			(hide yes)
			(effects
				(font
					(size 1.27 1.27)
				)
			)
		)
		(property "Value" ""
			(at 0 0 180)
			(layer "F.Fab")
			(effects
				(font
					(size 1.27 1.27)
				)
			)
		)
		(duplicate_pad_numbers_are_jumpers no)
		(fp_rect
			(start 0.3048 0.9906)
			(end -0.3048 -0.1016)
			(stroke
				(width 0)
				(type default)
			)
			(fill no)
			(layer "F.CrtYd")
		)
		(fp_line
			(start 0.3048 0.9906)
			(end 0.3048 -0.1016)
			(stroke
				(width 0.1)
				(type default)
			)
			(layer "F.Fab")
		)
		(fp_line
			(start 0.3048 -0.1016)
			(end -0.3048 -0.1016)
			(stroke
				(width 0.1)
				(type default)
			)
			(layer "F.Fab")
		)
		(fp_line
			(start -0.3048 0.9906)
			(end 0.3048 0.9906)
			(stroke
				(width 0.1)
				(type default)
			)
			(layer "F.Fab")
		)
		(fp_line
			(start -0.3048 -0.1016)
			(end -0.3048 0.9906)
			(stroke
				(width 0.1)
				(type default)
			)
			(layer "F.Fab")
		)
		(pad "1" smd rect
			(at 0 0 180)
			(size 0.508 0.508)
			(layers "F.Cu" "F.Mask" "F.Paste")
			(net "PWRGD_P5V_STBY")
		)
		(pad "2" smd rect
			(at 0 0.889 180)
			(size 0.508 0.508)
			(layers "F.Cu" "F.Mask" "F.Paste")
			(net "AGND_P3V3_STBY")
		)
		(zone
			(layer "F.Cu")
			(hatch none 0.5)
			(connect_pads
				(clearance 0)
			)
			(min_thickness 0.25)
			(keepout
				(tracks not_allowed)
				(vias allowed)
				(pads allowed)
				(copperpour not_allowed)
				(footprints allowed)
			)
			(placement
				(enabled no)
				(sheetname "")
			)
			(fill
				(thermal_gap 0.5)
				(thermal_bridge_width 0.5)
				(island_removal_mode 0)
			)
			(polygon
				(pts
					(xy 463.1309 -24.6253) (xy 463.1309 -24.2443) (xy 463.6389 -24.2443) (xy 463.6389 -24.6253)
				)
			)
		)
		(zone
			(layer "F.Cu")
			(hatch none 0.5)
			(connect_pads
				(clearance 0)
			)
			(min_thickness 0.25)
			(keepout
				(tracks allowed)
				(vias not_allowed)
				(pads allowed)
				(copperpour not_allowed)
				(footprints allowed)
			)
			(placement
				(enabled no)
				(sheetname "")
			)
			(fill
				(thermal_gap 0.5)
				(thermal_bridge_width 0.5)
				(island_removal_mode 0)
			)
			(polygon
				(pts
					(xy 463.1309 -24.6253) (xy 463.1309 -24.2443) (xy 463.6389 -24.2443) (xy 463.6389 -24.6253)
				)
			)
		)
	)
	(footprint ""
		(layer "F.Cu")
		(at 338.074 -11.684 90)
		(property "Reference" "C7G27"
			(at 0 0 90)
			(layer "F.SilkS")
			(hide yes)
			(effects
				(font
					(size 1.27 1.27)
				)
			)
		)
		(property "Value" ""
			(at 0 0 90)
			(layer "F.Fab")
			(effects
				(font
					(size 1.27 1.27)
				)
			)
		)
		(duplicate_pad_numbers_are_jumpers no)
		(fp_rect
			(start 0.7239 -0.2159)
			(end -0.7239 1.9939)
			(stroke
				(width 0)
				(type default)
			)
			(fill no)
			(layer "F.CrtYd")
		)
		(fp_line
			(start 0.7239 -0.2159)
			(end -0.7239 -0.2159)
			(stroke
				(width 0.1)
				(type default)
			)
			(layer "F.Fab")
		)
		(fp_line
			(start -0.7239 -0.2159)
			(end -0.7239 1.9939)
			(stroke
				(width 0.1)
				(type default)
			)
			(layer "F.Fab")
		)
		(fp_line
			(start 0.7239 1.9939)
			(end 0.7239 -0.2159)
			(stroke
				(width 0.1)
				(type default)
			)
			(layer "F.Fab")
		)
		(fp_line
			(start -0.7239 1.9939)
			(end 0.7239 1.9939)
			(stroke
				(width 0.1)
				(type default)
			)
			(layer "F.Fab")
		)
		(pad "1" smd rect
			(at 0 0 90)
			(size 1.27 1.016)
			(layers "F.Cu" "F.Mask" "F.Paste")
			(net "PVDDQ_ABC")
		)
		(pad "2" smd rect
			(at 0 1.778 90)
			(size 1.27 1.016)
			(layers "F.Cu" "F.Mask" "F.Paste")
			(net "GND")
		)
		(zone
			(layer "F.Cu")
			(hatch none 0.5)
			(connect_pads
				(clearance 0)
			)
			(min_thickness 0.25)
			(keepout
				(tracks not_allowed)
				(vias allowed)
				(pads allowed)
				(copperpour not_allowed)
				(footprints allowed)
			)
			(placement
				(enabled no)
				(sheetname "")
			)
			(fill
				(thermal_gap 0.5)
				(thermal_bridge_width 0.5)
				(island_removal_mode 0)
			)
			(polygon
				(pts
					(xy 338.582 -12.319) (xy 338.582 -11.049) (xy 339.344 -11.049) (xy 339.344 -12.319)
				)
			)
		)
	)
	(footprint ""
		(layer "F.Cu")
		(at 105.712768 -79.6036 180)
		(property "Reference" "C2D18"
			(at 0 0 180)
			(layer "F.SilkS")
			(hide yes)
			(effects
				(font
					(size 1.27 1.27)
				)
			)
		)
		(property "Value" ""
			(at 0 0 180)
			(layer "F.Fab")
			(effects
				(font
					(size 1.27 1.27)
				)
			)
		)
		(duplicate_pad_numbers_are_jumpers no)
		(fp_poly
			(pts
				(xy -0.4953 -0.2032) (xy 0.4953 -0.2032) (xy 0.4953 1.6002) (xy -0.4953 1.6002)
			)
			(stroke
				(width 0)
				(type default)
			)
			(fill no)
			(layer "F.CrtYd")
		)
		(fp_line
			(start 0.4953 1.6002)
			(end -0.4953 1.6002)
			(stroke
				(width 0.1)
				(type default)
			)
			(layer "F.Fab")
		)
		(fp_line
			(start 0.4953 -0.2032)
			(end 0.4953 1.6002)
			(stroke
				(width 0.1)
				(type default)
			)
			(layer "F.Fab")
		)
		(fp_line
			(start -0.4953 1.6002)
			(end -0.4953 -0.2032)
			(stroke
				(width 0.1)
				(type default)
			)
			(layer "F.Fab")
		)
		(fp_line
			(start -0.4953 -0.2032)
			(end 0.4953 -0.2032)
			(stroke
				(width 0.1)
				(type default)
			)
			(layer "F.Fab")
		)
		(pad "1" smd rect
			(at 0 0 180)
			(size 0.762 0.889)
			(layers "F.Cu" "F.Mask" "F.Paste")
			(net "PVCCMCP_CPU1")
		)
		(pad "2" smd rect
			(at 0 1.397 180)
			(size 0.762 0.889)
			(layers "F.Cu" "F.Mask" "F.Paste")
			(net "GND")
		)
		(zone
			(layer "F.Cu")
			(hatch none 0.5)
			(connect_pads
				(clearance 0)
			)
			(min_thickness 0.25)
			(keepout
				(tracks not_allowed)
				(vias allowed)
				(pads allowed)
				(copperpour not_allowed)
				(footprints allowed)
			)
			(placement
				(enabled no)
				(sheetname "")
			)
			(fill
				(thermal_gap 0.5)
				(thermal_bridge_width 0.5)
				(island_removal_mode 0)
			)
			(polygon
				(pts
					(xy 106.093768 -80.0481) (xy 105.331768 -80.0481) (xy 105.331768 -80.5561) (xy 106.093768 -80.5561)
				)
			)
		)
	)
)
